# T6G (Grand Teton) — schematic netlist excerpt (pin names and nets, part order shuffled) for the footprints in the layout excerpt that follows; sources: Cadence DE-HDL packaged netlist, KiCad conversion of 04192023_DAF0TMB3IC0_F0TG_MB_C_brd_V02_OCP.brd

U243  NC7SB3157  NC7SB3157P6X EMPTY  pkg SMLF  page 143
  B1  = OCP_SFF_NOT_PRSNT_RBT_ARB_IN
  GND  = GND
  B0  = OCP_SFF_RBT_ARB_OUT
  A  = OCP_SFF_RBT_ARB_IN_MUX2
  VCC  = P3V3_AUX
  S  = OCP_SFF_PRSNT_ALL_R1_N

R4075  Q_RES  0 5% CHIP  pkg 0402LF  page 233 : A = CLK_GEN2_BMC_RC_OE_N ; B = CLK_GEN2_BMC_RC_OE_R3_N

(kicad_pcb
	(version 20260206)
	(generator "pcbnew")
	(generator_version "10.0")
	(general
		(thickness 1.6)
		(legacy_teardrops no)
	)
	(paper "A4")
	(title_block
		(title "04192023_DAF0TMB3IC0_F0TG_MB_C_brd_V02_OCP.brd")
		(comment 1 "Grand Teton / footprints 1545-1546 of 8354")
	)
	(layers
		(0 "F.Cu" signal "TOP")
		(4 "In1.Cu" signal "GND")
		(6 "In2.Cu" signal "IN1")
		(8 "In3.Cu" signal "GND1")
		(10 "In4.Cu" signal "IN2")
		(12 "In5.Cu" signal "GND2")
		(14 "In6.Cu" signal "IN3")
		(16 "In7.Cu" signal "GND3")
		(18 "In8.Cu" signal "VCC")
		(20 "In9.Cu" signal "VCC1")
		(22 "In10.Cu" signal "GND4")
		(24 "In11.Cu" signal "IN4")
		(26 "In12.Cu" signal "GND5")
		(28 "In13.Cu" signal "IN5")
		(30 "In14.Cu" signal "GND6")
		(32 "In15.Cu" signal "IN6")
		(34 "In16.Cu" signal "GND7")
		(2 "B.Cu" signal "BOTTOM")
		(9 "F.Adhes" user "F.Adhesive")
		(11 "B.Adhes" user "B.Adhesive")
		(13 "F.Paste" user "Package Geometry/Pastemask Top")
		(15 "B.Paste" user "Package Geometry/Pastemask Bottom")
		(5 "F.SilkS" user "Ref Des/Silkscreen Top")
		(7 "B.SilkS" user "Ref Des/Silkscreen Bottom")
		(1 "F.Mask" user "Board Geometry/Soldermask Top")
		(3 "B.Mask" user "Board Geometry/Soldermask Bottom")
		(17 "Dwgs.User" user "User.Drawings")
		(19 "Cmts.User" user "User.Comments")
		(21 "Eco1.User" user "User.Eco1")
		(23 "Eco2.User" user "User.Eco2")
		(25 "Edge.Cuts" user "Board Geometry/Outline")
		(27 "Margin" user)
		(31 "F.CrtYd" user "Package Geometry/Place Bound Top")
		(29 "B.CrtYd" user "Package Geometry/Place Bound Bottom")
		(35 "F.Fab" user "Ref Des/Assembly Top")
		(33 "B.Fab" user "Ref Des/Assembly Bottom")
	)
	(footprint ""
		(layer "F.Cu")
		(at 153.88463 -98.355658)
		(property "Reference" "U243"
			(at -3.017774 -1.730502 0)
			(unlocked yes)
			(layer "F.SilkS")
			(effects
				(font
					(size 0.7874 0.5842)
					(thickness 0.1524)
				)
			)
		)
		(property "Value" ""
			(at 0 0 0)
			(layer "F.Fab")
			(effects
				(font
					(size 1.27 1.27)
				)
			)
		)
		(duplicate_pad_numbers_are_jumpers no)
		(fp_line
			(start -1.7272 1.1176)
			(end -1.7272 -1.1176)
			(stroke
				(width 0.1524)
				(type default)
			)
			(layer "F.SilkS")
		)
		(fp_line
			(start -0.254 -1.1176)
			(end -1.7272 -1.1176)
			(stroke
				(width 0.1524)
				(type default)
			)
			(layer "F.SilkS")
		)
		(fp_line
			(start 0 -0.7366)
			(end -0.254 -1.1176)
			(stroke
				(width 0.1524)
				(type default)
			)
			(layer "F.SilkS")
		)
		(fp_line
			(start 0.254 -1.1176)
			(end 0 -0.7366)
			(stroke
				(width 0.1524)
				(type default)
			)
			(layer "F.SilkS")
		)
		(fp_line
			(start 1.7272 -1.1176)
			(end 0.254 -1.1176)
			(stroke
				(width 0.1524)
				(type default)
			)
			(layer "F.SilkS")
		)
		(fp_line
			(start 1.7272 -1.1176)
			(end 1.7272 1.1176)
			(stroke
				(width 0.1524)
				(type default)
			)
			(layer "F.SilkS")
		)
		(fp_line
			(start 1.7272 1.1176)
			(end -1.7272 1.1176)
			(stroke
				(width 0.1524)
				(type default)
			)
			(layer "F.SilkS")
		)
		(fp_poly
			(pts
				(xy -2.7178 -1.030986) (xy -1.9558 -0.649986) (xy -2.7178 -0.268986)
			)
			(stroke
				(width 0)
				(type default)
			)
			(fill yes)
			(layer "F.SilkS")
		)
		(fp_line
			(start -1.5748 -1.1176)
			(end -1.5748 1.1176)
			(stroke
				(width 0.1)
				(type default)
			)
			(layer "F.Fab")
		)
		(fp_line
			(start -1.5748 1.1176)
			(end 1.5748 1.1176)
			(stroke
				(width 0.1)
				(type default)
			)
			(layer "F.Fab")
		)
		(fp_line
			(start 1.5748 -1.1176)
			(end -1.5748 -1.1176)
			(stroke
				(width 0.1)
				(type default)
			)
			(layer "F.Fab")
		)
		(fp_line
			(start 1.5748 1.1176)
			(end 1.5748 -1.1176)
			(stroke
				(width 0.1)
				(type default)
			)
			(layer "F.Fab")
		)
		(fp_poly
			(pts
				(xy -1.9558 -0.649986) (xy -2.7178 -0.268986) (xy -2.7178 -1.030986)
			)
			(stroke
				(width 0)
				(type default)
			)
			(fill yes)
			(layer "F.Fab")
		)
		(pad "1" smd rect
			(at -0.999998 -0.649986 270)
			(size 0.3556 1.1176)
			(layers "F.Cu" "F.Mask" "F.Paste")
			(net "OCP_SFF_NOT_PRSNT_RBT_ARB_IN")
		)
		(pad "2" smd rect
			(at -0.999998 0 270)
			(size 0.3556 1.1176)
			(layers "F.Cu" "F.Mask" "F.Paste")
			(net "GND")
		)
		(pad "3" smd rect
			(at -0.999998 0.649986 270)
			(size 0.3556 1.1176)
			(layers "F.Cu" "F.Mask" "F.Paste")
			(net "OCP_SFF_RBT_ARB_OUT")
		)
		(pad "4" smd rect
			(at 0.999998 0.649986 270)
			(size 0.3556 1.1176)
			(layers "F.Cu" "F.Mask" "F.Paste")
			(net "OCP_SFF_RBT_ARB_IN_MUX2")
		)
		(pad "5" smd rect
			(at 0.999998 0 270)
			(size 0.3556 1.1176)
			(layers "F.Cu" "F.Mask" "F.Paste")
			(net "P3V3_AUX")
		)
		(pad "6" smd rect
			(at 0.999998 -0.649986 270)
			(size 0.3556 1.1176)
			(layers "F.Cu" "F.Mask" "F.Paste")
			(net "OCP_SFF_PRSNT_ALL_R1_N")
		)
	)
	(footprint ""
		(layer "F.Cu")
		(at 14.834108 -128.54559 90)
		(property "Reference" "R4075"
			(at 0 0 90)
			(layer "F.SilkS")
			(hide yes)
			(effects
				(font
					(size 1.27 1.27)
				)
			)
		)
		(property "Value" ""
			(at 0 0 90)
			(layer "F.Fab")
			(effects
				(font
					(size 1.27 1.27)
				)
			)
		)
		(duplicate_pad_numbers_are_jumpers no)
		(fp_line
			(start 0.7874 -0.4064)
			(end 0.7874 0.4064)
			(stroke
				(width 0.1524)
				(type default)
			)
			(layer "F.SilkS")
		)
		(fp_line
			(start -0.7874 -0.4064)
			(end 0.7874 -0.4064)
			(stroke
				(width 0.1524)
				(type default)
			)
			(layer "F.SilkS")
		)
		(fp_line
			(start 0.7874 0.4064)
			(end -0.7874 0.4064)
			(stroke
				(width 0.1524)
				(type default)
			)
			(layer "F.SilkS")
		)
		(fp_line
			(start -0.7874 0.4064)
			(end -0.7874 -0.4064)
			(stroke
				(width 0.1524)
				(type default)
			)
			(layer "F.SilkS")
		)
		(fp_line
			(start -0.12065 -0.305054)
			(end -0.12065 -0.2794)
			(stroke
				(width 0.1)
				(type default)
			)
			(layer "F.Fab")
		)
		(fp_line
			(start -0.67945 -0.305054)
			(end -0.12065 -0.305054)
			(stroke
				(width 0.1)
				(type default)
			)
			(layer "F.Fab")
		)
		(fp_line
			(start 0.67945 -0.3048)
			(end 0.67945 0.3048)
			(stroke
				(width 0.1)
				(type default)
			)
			(layer "F.Fab")
		)
		(fp_line
			(start 0.12065 -0.3048)
			(end 0.67945 -0.3048)
			(stroke
				(width 0.1)
				(type default)
			)
			(layer "F.Fab")
		)
		(fp_line
			(start 0.12065 -0.2794)
			(end 0.12065 -0.3048)
			(stroke
				(width 0.1)
				(type default)
			)
			(layer "F.Fab")
		)
		(fp_line
			(start -0.12065 -0.2794)
			(end 0.12065 -0.2794)
			(stroke
				(width 0.1)
				(type default)
			)
			(layer "F.Fab")
		)
		(fp_line
			(start 0.120396 0.2794)
			(end -0.12065 0.2794)
			(stroke
				(width 0.1)
				(type default)
			)
			(layer "F.Fab")
		)
		(fp_line
			(start -0.12065 0.2794)
			(end -0.12065 0.3048)
			(stroke
				(width 0.1)
				(type default)
			)
			(layer "F.Fab")
		)
		(fp_line
			(start 0.67945 0.3048)
			(end 0.120396 0.3048)
			(stroke
				(width 0.1)
				(type default)
			)
			(layer "F.Fab")
		)
		(fp_line
			(start 0.120396 0.3048)
			(end 0.120396 0.2794)
			(stroke
				(width 0.1)
				(type default)
			)
			(layer "F.Fab")
		)
		(fp_line
			(start -0.12065 0.3048)
			(end -0.67945 0.3048)
			(stroke
				(width 0.1)
				(type default)
			)
			(layer "F.Fab")
		)
		(fp_line
			(start -0.67945 0.3048)
			(end -0.67945 -0.305054)
			(stroke
				(width 0.1)
				(type default)
			)
			(layer "F.Fab")
		)
		(pad "1" smd circle
			(at -0.40005 0 90)
			(size 0 0)
			(layers "F.Cu" "F.Mask" "F.Paste")
			(net "CLK_GEN2_BMC_RC_OE_N")
		)
		(pad "2" smd circle
			(at 0.40005 0 90)
			(size 0 0)
			(layers "F.Cu" "F.Mask" "F.Paste")
			(net "CLK_GEN2_BMC_RC_OE_R3_N")
		)
	)
)
